# SCM (Grand Teton) — schematic netlist excerpt (pin names and nets, part order shuffled) for the footprints in the layout excerpt that follows; sources: Cadence DE-HDL packaged netlist, KiCad conversion of 12092022_DA0F0TMDCD0_F0T_Management_Board_D_brd_V3_OCP.brd

R337  Q_RES  120 1% CHIP  pkg 0402LF  page 20 : A = GND ; B = M_BMC_DDR4_MA<11>
R825  Q_RES  33.2 1% CHIP  pkg 0402LF  page 35 : A = RST_ROT_CPU_N ; B = RST_ROT_CPU_R_N

(kicad_pcb
	(version 20260206)
	(generator "pcbnew")
	(generator_version "10.0")
	(general
		(thickness 1.6)
		(legacy_teardrops no)
	)
	(paper "A4")
	(title_block
		(title "12092022_DA0F0TMDCD0_F0T_Management_Board_D_brd_V3_OCP.brd")
		(comment 1 "Grand Teton / footprints 1055-1056 of 1440")
	)
	(layers
		(0 "F.Cu" signal "TOP")
		(4 "In1.Cu" signal "GND")
		(6 "In2.Cu" signal "IN1")
		(8 "In3.Cu" signal "GND1")
		(10 "In4.Cu" signal "IN2")
		(12 "In5.Cu" signal "VCC")
		(14 "In6.Cu" signal "VCC1")
		(16 "In7.Cu" signal "IN3")
		(18 "In8.Cu" signal "GND2")
		(20 "In9.Cu" signal "IN4")
		(22 "In10.Cu" signal "GND3")
		(2 "B.Cu" signal "BOTTOM")
		(9 "F.Adhes" user "F.Adhesive")
		(11 "B.Adhes" user "B.Adhesive")
		(13 "F.Paste" user "Package Geometry/Pastemask Top")
		(15 "B.Paste" user "Package Geometry/Pastemask Bottom")
		(5 "F.SilkS" user "Ref Des/Silkscreen Top")
		(7 "B.SilkS" user "Ref Des/Silkscreen Bottom")
		(1 "F.Mask" user "Board Geometry/Soldermask Top")
		(3 "B.Mask" user "Board Geometry/Soldermask Bottom")
		(17 "Dwgs.User" user "User.Drawings")
		(19 "Cmts.User" user "User.Comments")
		(21 "Eco1.User" user "User.Eco1")
		(23 "Eco2.User" user "User.Eco2")
		(25 "Edge.Cuts" user "Board Geometry/Outline")
		(27 "Margin" user)
		(31 "F.CrtYd" user "Package Geometry/Place Bound Top")
		(29 "B.CrtYd" user "Package Geometry/Place Bound Bottom")
		(35 "F.Fab" user "Ref Des/Assembly Top")
		(33 "B.Fab" user "Ref Des/Assembly Bottom")
	)
	(footprint ""
		(layer "B.Cu")
		(at 12.319 -93.472 180)
		(property "Reference" "R825"
			(at 0 0 0)
			(layer "B.SilkS")
			(hide yes)
			(effects
				(font
					(size 1.27 1.27)
				)
				(justify mirror)
			)
		)
		(property "Value" ""
			(at 0 0 0)
			(layer "B.Fab")
			(effects
				(font
					(size 1.27 1.27)
				)
				(justify mirror)
			)
		)
		(duplicate_pad_numbers_are_jumpers no)
		(fp_line
			(start 0.7874 0.4064)
			(end 0.7874 -0.4064)
			(stroke
				(width 0.1524)
				(type default)
			)
			(layer "B.SilkS")
		)
		(fp_line
			(start 0.7874 -0.4064)
			(end -0.7874 -0.4064)
			(stroke
				(width 0.1524)
				(type default)
			)
			(layer "B.SilkS")
		)
		(fp_line
			(start -0.7874 0.4064)
			(end 0.7874 0.4064)
			(stroke
				(width 0.1524)
				(type default)
			)
			(layer "B.SilkS")
		)
		(fp_line
			(start -0.7874 -0.4064)
			(end -0.7874 0.4064)
			(stroke
				(width 0.1524)
				(type default)
			)
			(layer "B.SilkS")
		)
		(fp_line
			(start 0.67945 0.3048)
			(end 0.67945 -0.305054)
			(stroke
				(width 0.1)
				(type default)
			)
			(layer "B.Fab")
		)
		(fp_line
			(start 0.67945 -0.305054)
			(end 0.12065 -0.305054)
			(stroke
				(width 0.1)
				(type default)
			)
			(layer "B.Fab")
		)
		(fp_line
			(start 0.12065 0.3048)
			(end 0.67945 0.3048)
			(stroke
				(width 0.1)
				(type default)
			)
			(layer "B.Fab")
		)
		(fp_line
			(start 0.12065 0.2794)
			(end 0.12065 0.3048)
			(stroke
				(width 0.1)
				(type default)
			)
			(layer "B.Fab")
		)
		(fp_line
			(start 0.12065 -0.2794)
			(end -0.12065 -0.2794)
			(stroke
				(width 0.1)
				(type default)
			)
			(layer "B.Fab")
		)
		(fp_line
			(start 0.12065 -0.305054)
			(end 0.12065 -0.2794)
			(stroke
				(width 0.1)
				(type default)
			)
			(layer "B.Fab")
		)
		(fp_line
			(start -0.120396 0.3048)
			(end -0.120396 0.2794)
			(stroke
				(width 0.1)
				(type default)
			)
			(layer "B.Fab")
		)
		(fp_line
			(start -0.120396 0.2794)
			(end 0.12065 0.2794)
			(stroke
				(width 0.1)
				(type default)
			)
			(layer "B.Fab")
		)
		(fp_line
			(start -0.12065 -0.2794)
			(end -0.12065 -0.3048)
			(stroke
				(width 0.1)
				(type default)
			)
			(layer "B.Fab")
		)
		(fp_line
			(start -0.12065 -0.3048)
			(end -0.67945 -0.3048)
			(stroke
				(width 0.1)
				(type default)
			)
			(layer "B.Fab")
		)
		(fp_line
			(start -0.67945 0.3048)
			(end -0.120396 0.3048)
			(stroke
				(width 0.1)
				(type default)
			)
			(layer "B.Fab")
		)
		(fp_line
			(start -0.67945 -0.3048)
			(end -0.67945 0.3048)
			(stroke
				(width 0.1)
				(type default)
			)
			(layer "B.Fab")
		)
		(pad "1" smd circle
			(at 0.40005 0)
			(size 0 0)
			(layers "B.Cu" "B.Mask" "B.Paste")
			(net "RST_ROT_CPU_N")
		)
		(pad "2" smd circle
			(at -0.40005 0)
			(size 0 0)
			(layers "B.Cu" "B.Mask" "B.Paste")
			(net "RST_ROT_CPU_R_N")
		)
	)
	(footprint ""
		(layer "B.Cu")
		(at 76.691744 -35.540188 -90)
		(property "Reference" "R337"
			(at 0 0 90)
			(layer "B.SilkS")
			(hide yes)
			(effects
				(font
					(size 1.27 1.27)
				)
				(justify mirror)
			)
		)
		(property "Value" ""
			(at 0 0 90)
			(layer "B.Fab")
			(effects
				(font
					(size 1.27 1.27)
				)
				(justify mirror)
			)
		)
		(duplicate_pad_numbers_are_jumpers no)
		(fp_line
			(start -0.7874 0.4064)
			(end 0.7874 0.4064)
			(stroke
				(width 0.1524)
				(type default)
			)
			(layer "B.SilkS")
		)
		(fp_line
			(start 0.7874 0.4064)
			(end 0.7874 -0.4064)
			(stroke
				(width 0.1524)
				(type default)
			)
			(layer "B.SilkS")
		)
		(fp_line
			(start -0.7874 -0.4064)
			(end -0.7874 0.4064)
			(stroke
				(width 0.1524)
				(type default)
			)
			(layer "B.SilkS")
		)
		(fp_line
			(start 0.7874 -0.4064)
			(end -0.7874 -0.4064)
			(stroke
				(width 0.1524)
				(type default)
			)
			(layer "B.SilkS")
		)
		(fp_line
			(start -0.67945 0.3048)
			(end -0.120396 0.3048)
			(stroke
				(width 0.1)
				(type default)
			)
			(layer "B.Fab")
		)
		(fp_line
			(start -0.120396 0.3048)
			(end -0.120396 0.2794)
			(stroke
				(width 0.1)
				(type default)
			)
			(layer "B.Fab")
		)
		(fp_line
			(start 0.12065 0.3048)
			(end 0.67945 0.3048)
			(stroke
				(width 0.1)
				(type default)
			)
			(layer "B.Fab")
		)
		(fp_line
			(start 0.67945 0.3048)
			(end 0.67945 -0.305054)
			(stroke
				(width 0.1)
				(type default)
			)
			(layer "B.Fab")
		)
		(fp_line
			(start -0.120396 0.2794)
			(end 0.12065 0.2794)
			(stroke
				(width 0.1)
				(type default)
			)
			(layer "B.Fab")
		)
		(fp_line
			(start 0.12065 0.2794)
			(end 0.12065 0.3048)
			(stroke
				(width 0.1)
				(type default)
			)
			(layer "B.Fab")
		)
		(fp_line
			(start -0.12065 -0.2794)
			(end -0.12065 -0.3048)
			(stroke
				(width 0.1)
				(type default)
			)
			(layer "B.Fab")
		)
		(fp_line
			(start 0.12065 -0.2794)
			(end -0.12065 -0.2794)
			(stroke
				(width 0.1)
				(type default)
			)
			(layer "B.Fab")
		)
		(fp_line
			(start -0.67945 -0.3048)
			(end -0.67945 0.3048)
			(stroke
				(width 0.1)
				(type default)
			)
			(layer "B.Fab")
		)
		(fp_line
			(start -0.12065 -0.3048)
			(end -0.67945 -0.3048)
			(stroke
				(width 0.1)
				(type default)
			)
			(layer "B.Fab")
		)
		(fp_line
			(start 0.12065 -0.305054)
			(end 0.12065 -0.2794)
			(stroke
				(width 0.1)
				(type default)
			)
			(layer "B.Fab")
		)
		(fp_line
			(start 0.67945 -0.305054)
			(end 0.12065 -0.305054)
			(stroke
				(width 0.1)
				(type default)
			)
			(layer "B.Fab")
		)
		(pad "1" smd circle
			(at 0.40005 0 90)
			(size 0 0)
			(layers "B.Cu" "B.Mask" "B.Paste")
			(net "GND")
		)
		(pad "2" smd circle
			(at -0.40005 0 90)
			(size 0 0)
			(layers "B.Cu" "B.Mask" "B.Paste")
			(net "M_BMC_DDR4_MA<11>")
		)
	)
)
